(kicad_pcb
	(version 20260206)
	(generator "pcbnew")
	(generator_version "10.0")
	(general
		(thickness 1.6)
		(legacy_teardrops no)
	)
	(paper "A4")
	(title_block
		(title "12092022_DA0F0TYB4D0_F0T_Panel_BD_Front_D_brd_v02_OCP.brd")
		(comment 1 "Grand Teton / footprints 121-125 of 128")
	)
	(layers
		(0 "F.Cu" signal "TOP")
		(4 "In1.Cu" signal "GND")
		(6 "In2.Cu" signal "GND1")
		(2 "B.Cu" signal "BOTTOM")
		(9 "F.Adhes" user "F.Adhesive")
		(11 "B.Adhes" user "B.Adhesive")
		(13 "F.Paste" user "Package Geometry/Pastemask Top")
		(15 "B.Paste" user "Package Geometry/Pastemask Bottom")
		(5 "F.SilkS" user "Ref Des/Silkscreen Top")
		(7 "B.SilkS" user "Ref Des/Silkscreen Bottom")
		(1 "F.Mask" user "Board Geometry/Soldermask Top")
		(3 "B.Mask" user "Board Geometry/Soldermask Bottom")
		(17 "Dwgs.User" user "User.Drawings")
		(19 "Cmts.User" user "User.Comments")
		(21 "Eco1.User" user "User.Eco1")
		(23 "Eco2.User" user "User.Eco2")
		(25 "Edge.Cuts" user "Board Geometry/Outline")
		(27 "Margin" user)
		(31 "F.CrtYd" user "Package Geometry/Place Bound Top")
		(29 "B.CrtYd" user "Package Geometry/Place Bound Bottom")
		(35 "F.Fab" user "Ref Des/Assembly Top")
		(33 "B.Fab" user "Ref Des/Assembly Bottom")
	)
	(footprint ""
		(layer "F.Cu")
		(at 94.02953 -62.894972 90)
		(property "Reference" "X1"
			(at 4.388358 -1.82753 0)
			(unlocked yes)
			(layer "F.SilkS")
			(effects
				(font
					(size 0.7874 0.5842)
					(thickness 0.1524)
				)
				(justify left)
			)
		)
		(property "Value" ""
			(at 0 0 90)
			(layer "F.Fab")
			(effects
				(font
					(size 1.27 1.27)
				)
			)
		)
		(property "Device Type" "TP_TDR_4P_FTS_MPKT4_H025P0200_IO_TP15_TP_TDR_4P_DIP"
			(at 1.30175 1.27 180)
			(unlocked yes)
			(layer "F.Fab")
			(hide yes)
			(effects
				(font
					(size 0.635 0.4064)
					(thickness 0.1524)
				)
			)
		)
		(property "User Part Number" "TP15"
			(at 1.30175 1.27 180)
			(unlocked yes)
			(layer "Cmts.User")
			(hide yes)
			(effects
				(font
					(size 0.635 0.4064)
					(thickness 0.1524)
				)
			)
		)
		(duplicate_pad_numbers_are_jumpers no)
		(fp_line
			(start 2.54 -1.27)
			(end 0 -1.27)
			(stroke
				(width 0.1524)
				(type default)
			)
			(layer "F.SilkS")
		)
		(fp_line
			(start 0 -1.27)
			(end 0 -0.635)
			(stroke
				(width 0.1524)
				(type default)
			)
			(layer "F.SilkS")
		)
		(fp_line
			(start 2.54 -1.1303)
			(end 2.54 -1.27)
			(stroke
				(width 0.1524)
				(type default)
			)
			(layer "F.SilkS")
		)
		(fp_line
			(start 0 0.635)
			(end 0 1.905)
			(stroke
				(width 0.1524)
				(type default)
			)
			(layer "F.SilkS")
		)
		(fp_line
			(start 2.54 1.4097)
			(end 2.54 1.1303)
			(stroke
				(width 0.1524)
				(type default)
			)
			(layer "F.SilkS")
		)
		(fp_line
			(start 0 3.175)
			(end 0 3.81)
			(stroke
				(width 0.1524)
				(type default)
			)
			(layer "F.SilkS")
		)
		(fp_line
			(start 2.54 3.81)
			(end 2.54 3.6703)
			(stroke
				(width 0.1524)
				(type default)
			)
			(layer "F.SilkS")
		)
		(fp_line
			(start 0 3.81)
			(end 2.54 3.81)
			(stroke
				(width 0.1524)
				(type default)
			)
			(layer "F.SilkS")
		)
		(fp_poly
			(pts
				(xy -0.761746 0) (xy -2.285746 -0.762) (xy -2.285746 0.762)
			)
			(stroke
				(width 0)
				(type default)
			)
			(fill yes)
			(layer "F.SilkS")
		)
		(fp_line
			(start 2.54 -1.27)
			(end 0 -1.27)
			(stroke
				(width 0.1)
				(type default)
			)
			(layer "F.Fab")
		)
		(fp_line
			(start 0 -1.27)
			(end 0 3.81)
			(stroke
				(width 0.1)
				(type default)
			)
			(layer "F.Fab")
		)
		(fp_line
			(start 2.54 3.81)
			(end 2.54 -1.27)
			(stroke
				(width 0.1)
				(type default)
			)
			(layer "F.Fab")
		)
		(fp_line
			(start 0 3.81)
			(end 2.54 3.81)
			(stroke
				(width 0.1)
				(type default)
			)
			(layer "F.Fab")
		)
		(fp_poly
			(pts
				(xy -0.761746 0) (xy -2.285746 -0.762) (xy -2.285746 0.762)
			)
			(stroke
				(width 0)
				(type default)
			)
			(fill yes)
			(layer "F.Fab")
		)
		(pad "1" thru_hole circle
			(at 0 0 90)
			(size 1.0033 1.0033)
			(drill 0.249936)
			(layers "*.Cu" "*.Mask")
			(remove_unused_layers no)
			(net "TDR_DIFF_85_TOP_DP")
			(clearance 0.10795)
			(thermal_gap 0.10795)
			(padstack
				(mode front_inner_back)
				(layer "Inner"
					(shape circle)
					(size 0.8001 0.8001)
					(clearance 0.1524)
				)
				(layer "B.Cu"
					(shape circle)
					(size 1.0033 1.0033)
					(clearance 0.10795)
				)
			)
		)
		(pad "2" thru_hole circle
			(at 2.54 0 90)
			(size 1.9939 1.9939)
			(drill 0.249936)
			(layers "*.Cu" "*.Mask")
			(remove_unused_layers no)
			(net "GND_TDR")
			(clearance 0.10795)
			(thermal_gap 0.10795)
			(padstack
				(mode front_inner_back)
				(layer "Inner"
					(shape circle)
					(size 0.8001 0.8001)
					(clearance 0.1524)
				)
				(layer "B.Cu"
					(shape circle)
					(size 1.9939 1.9939)
					(clearance 0.10795)
				)
			)
		)
		(pad "3" thru_hole circle
			(at 2.54 2.54 90)
			(size 1.9939 1.9939)
			(drill 0.249936)
			(layers "*.Cu" "*.Mask")
			(remove_unused_layers no)
			(net "GND_TDR")
			(clearance 0.10795)
			(thermal_gap 0.10795)
			(padstack
				(mode front_inner_back)
				(layer "Inner"
					(shape circle)
					(size 0.8001 0.8001)
					(clearance 0.1524)
				)
				(layer "B.Cu"
					(shape circle)
					(size 1.9939 1.9939)
					(clearance 0.10795)
				)
			)
		)
		(pad "4" thru_hole circle
			(at 0 2.54 90)
			(size 1.0033 1.0033)
			(drill 0.249936)
			(layers "*.Cu" "*.Mask")
			(remove_unused_layers no)
			(net "TDR_DIFF_85_TOP_DN")
			(clearance 0.10795)
			(thermal_gap 0.10795)
			(padstack
				(mode front_inner_back)
				(layer "Inner"
					(shape circle)
					(size 0.8001 0.8001)
					(clearance 0.1524)
				)
				(layer "B.Cu"
					(shape circle)
					(size 1.0033 1.0033)
					(clearance 0.10795)
				)
			)
		)
	)
	(footprint ""
		(layer "F.Cu")
		(at 24.003 -28.067 180)
		(property "Reference" "U10"
			(at 2.00533 -0.762 90)
			(unlocked yes)
			(layer "F.SilkS")
			(effects
				(font
					(size 0.7874 0.5842)
					(thickness 0.1524)
				)
				(justify left)
			)
		)
		(property "Value" ""
			(at 0 0 180)
			(layer "F.Fab")
			(effects
				(font
					(size 1.27 1.27)
				)
			)
		)
		(duplicate_pad_numbers_are_jumpers no)
		(fp_line
			(start 0.517398 1.500124)
			(end -0.517398 1.500124)
			(stroke
				(width 0.1524)
				(type default)
			)
			(layer "F.SilkS")
		)
		(fp_line
			(start 0.517398 -1.500124)
			(end 0.517398 1.500124)
			(stroke
				(width 0.1524)
				(type default)
			)
			(layer "F.SilkS")
		)
		(fp_line
			(start -0.517398 1.500124)
			(end -0.517398 -1.500124)
			(stroke
				(width 0.1524)
				(type default)
			)
			(layer "F.SilkS")
		)
		(fp_line
			(start -0.517398 -1.500124)
			(end 0.517398 -1.500124)
			(stroke
				(width 0.1524)
				(type default)
			)
			(layer "F.SilkS")
		)
		(fp_poly
			(pts
				(xy -1.5113 -0.750062) (xy -2.1463 -1.067562) (xy -2.1463 -0.432562)
			)
			(stroke
				(width 0)
				(type default)
			)
			(fill yes)
			(layer "F.SilkS")
		)
		(fp_line
			(start 0.700024 1.500124)
			(end -0.700024 1.500124)
			(stroke
				(width 0.1)
				(type default)
			)
			(layer "F.Fab")
		)
		(fp_line
			(start 0.700024 -1.500124)
			(end 0.700024 1.500124)
			(stroke
				(width 0.1)
				(type default)
			)
			(layer "F.Fab")
		)
		(fp_line
			(start -0.700024 1.500124)
			(end -0.700024 -1.500124)
			(stroke
				(width 0.1)
				(type default)
			)
			(layer "F.Fab")
		)
		(fp_line
			(start -0.700024 -1.500124)
			(end 0.700024 -1.500124)
			(stroke
				(width 0.1)
				(type default)
			)
			(layer "F.Fab")
		)
		(fp_poly
			(pts
				(xy -1.5113 -0.750062) (xy -2.1463 -1.067562) (xy -2.1463 -0.432562)
			)
			(stroke
				(width 0)
				(type default)
			)
			(fill yes)
			(layer "F.Fab")
		)
		(pad "1" smd rect
			(at -0.999998 -0.750062 180)
			(size 0.7112 1.016)
			(layers "F.Cu" "F.Mask" "F.Paste")
			(net "GND")
		)
		(pad "2" smd rect
			(at -0.999998 0.94996 90)
			(size 0.6096 0.7112)
			(layers "F.Cu" "F.Mask" "F.Paste")
			(net "UART_DEBUG_R_TX")
		)
		(pad "3" smd rect
			(at 0.999998 0.94996 90)
			(size 0.6096 0.7112)
			(layers "F.Cu" "F.Mask" "F.Paste")
			(net "UART_DEBUG_R_RX")
		)
		(pad "4" smd rect
			(at 0.999998 -0.94996 90)
			(size 0.6096 0.7112)
			(layers "F.Cu" "F.Mask" "F.Paste")
			(net "P5V_STBY_DEBUG")
		)
	)
	(footprint ""
		(layer "F.Cu")
		(at 15.875 -49.149 180)
		(property "Reference" "R55"
			(at -2.54 -0.02667 0)
			(unlocked yes)
			(layer "F.SilkS")
			(effects
				(font
					(size 0.7874 0.5842)
					(thickness 0.1524)
				)
			)
		)
		(property "Value" ""
			(at 0 0 180)
			(layer "F.Fab")
			(effects
				(font
					(size 1.27 1.27)
				)
			)
		)
		(duplicate_pad_numbers_are_jumpers no)
		(fp_line
			(start 0.7874 0.4064)
			(end -0.7874 0.4064)
			(stroke
				(width 0.1524)
				(type default)
			)
			(layer "F.SilkS")
		)
		(fp_line
			(start 0.7874 -0.4064)
			(end 0.7874 0.4064)
			(stroke
				(width 0.1524)
				(type default)
			)
			(layer "F.SilkS")
		)
		(fp_line
			(start -0.7874 0.4064)
			(end -0.7874 -0.4064)
			(stroke
				(width 0.1524)
				(type default)
			)
			(layer "F.SilkS")
		)
		(fp_line
			(start -0.7874 -0.4064)
			(end 0.7874 -0.4064)
			(stroke
				(width 0.1524)
				(type default)
			)
			(layer "F.SilkS")
		)
		(fp_line
			(start 0.67945 0.3048)
			(end 0.120396 0.3048)
			(stroke
				(width 0.1)
				(type default)
			)
			(layer "F.Fab")
		)
		(fp_line
			(start 0.67945 -0.3048)
			(end 0.67945 0.3048)
			(stroke
				(width 0.1)
				(type default)
			)
			(layer "F.Fab")
		)
		(fp_line
			(start 0.12065 -0.2794)
			(end 0.12065 -0.3048)
			(stroke
				(width 0.1)
				(type default)
			)
			(layer "F.Fab")
		)
		(fp_line
			(start 0.12065 -0.3048)
			(end 0.67945 -0.3048)
			(stroke
				(width 0.1)
				(type default)
			)
			(layer "F.Fab")
		)
		(fp_line
			(start 0.120396 0.3048)
			(end 0.120396 0.2794)
			(stroke
				(width 0.1)
				(type default)
			)
			(layer "F.Fab")
		)
		(fp_line
			(start 0.120396 0.2794)
			(end -0.12065 0.2794)
			(stroke
				(width 0.1)
				(type default)
			)
			(layer "F.Fab")
		)
		(fp_line
			(start -0.12065 0.3048)
			(end -0.67945 0.3048)
			(stroke
				(width 0.1)
				(type default)
			)
			(layer "F.Fab")
		)
		(fp_line
			(start -0.12065 0.2794)
			(end -0.12065 0.3048)
			(stroke
				(width 0.1)
				(type default)
			)
			(layer "F.Fab")
		)
		(fp_line
			(start -0.12065 -0.2794)
			(end 0.12065 -0.2794)
			(stroke
				(width 0.1)
				(type default)
			)
			(layer "F.Fab")
		)
		(fp_line
			(start -0.12065 -0.305054)
			(end -0.12065 -0.2794)
			(stroke
				(width 0.1)
				(type default)
			)
			(layer "F.Fab")
		)
		(fp_line
			(start -0.67945 0.3048)
			(end -0.67945 -0.305054)
			(stroke
				(width 0.1)
				(type default)
			)
			(layer "F.Fab")
		)
		(fp_line
			(start -0.67945 -0.305054)
			(end -0.12065 -0.305054)
			(stroke
				(width 0.1)
				(type default)
			)
			(layer "F.Fab")
		)
		(pad "1" smd circle
			(at -0.40005 0 180)
			(size 0 0)
			(layers "F.Cu" "F.Mask" "F.Paste")
			(net "P3V3_STBY")
		)
		(pad "2" smd circle
			(at 0.40005 0 180)
			(size 0 0)
			(layers "F.Cu" "F.Mask" "F.Paste")
			(net "PD_FRU_WP")
		)
	)
	(footprint ""
		(layer "F.Cu")
		(at 2.62001 -5.100066)
		(property "Reference" "D2"
			(at -1.98501 -2.64922 0)
			(unlocked yes)
			(layer "F.SilkS")
			(effects
				(font
					(size 0.7874 0.5842)
					(thickness 0.1524)
				)
				(justify left)
			)
		)
		(property "Value" ""
			(at 0 0 0)
			(layer "F.Fab")
			(effects
				(font
					(size 1.27 1.27)
				)
			)
		)
		(duplicate_pad_numbers_are_jumpers no)
		(fp_line
			(start -1.080008 -1.999996)
			(end 3.620008 -1.999996)
			(stroke
				(width 0.1524)
				(type default)
			)
			(layer "F.SilkS")
		)
		(fp_line
			(start -1.080008 3.999992)
			(end -1.080008 -1.999996)
			(stroke
				(width 0.1524)
				(type default)
			)
			(layer "F.SilkS")
		)
		(fp_line
			(start -0.230124 3.999992)
			(end -1.080008 3.999992)
			(stroke
				(width 0.1524)
				(type default)
			)
			(layer "F.SilkS")
		)
		(fp_line
			(start -0.230124 5.199888)
			(end -0.230124 3.999992)
			(stroke
				(width 0.1524)
				(type default)
			)
			(layer "F.SilkS")
		)
		(fp_line
			(start 2.770124 3.999992)
			(end 2.770124 5.199888)
			(stroke
				(width 0.1524)
				(type default)
			)
			(layer "F.SilkS")
		)
		(fp_line
			(start 3.620008 -1.999996)
			(end 3.620008 3.999992)
			(stroke
				(width 0.1524)
				(type default)
			)
			(layer "F.SilkS")
		)
		(fp_line
			(start 3.620008 3.999992)
			(end 2.770124 3.999992)
			(stroke
				(width 0.1524)
				(type default)
			)
			(layer "F.SilkS")
		)
		(fp_arc
			(start 1.27 6.700012)
			(mid 0.209252 6.260636)
			(end -0.230124 5.199888)
			(stroke
				(width 0.1524)
				(type default)
			)
			(layer "F.SilkS")
		)
		(fp_arc
			(start 2.770124 5.199888)
			(mid 2.330748 6.260636)
			(end 1.27 6.700012)
			(stroke
				(width 0.1524)
				(type default)
			)
			(layer "F.SilkS")
		)
		(fp_line
			(start -1.080008 -1.999996)
			(end 3.620008 -1.999996)
			(stroke
				(width 0.1)
				(type default)
			)
			(layer "F.Fab")
		)
		(fp_line
			(start -1.080008 3.999992)
			(end -1.080008 -1.999996)
			(stroke
				(width 0.1)
				(type default)
			)
			(layer "F.Fab")
		)
		(fp_line
			(start -0.230124 3.999992)
			(end -1.080008 3.999992)
			(stroke
				(width 0.1)
				(type default)
			)
			(layer "F.Fab")
		)
		(fp_line
			(start -0.230124 5.199888)
			(end -0.230124 3.999992)
			(stroke
				(width 0.1)
				(type default)
			)
			(layer "F.Fab")
		)
		(fp_line
			(start 2.770124 3.999992)
			(end 2.770124 5.199888)
			(stroke
				(width 0.1)
				(type default)
			)
			(layer "F.Fab")
		)
		(fp_line
			(start 3.620008 -1.999996)
			(end 3.620008 3.999992)
			(stroke
				(width 0.1)
				(type default)
			)
			(layer "F.Fab")
		)
		(fp_line
			(start 3.620008 3.999992)
			(end 2.770124 3.999992)
			(stroke
				(width 0.1)
				(type default)
			)
			(layer "F.Fab")
		)
		(fp_arc
			(start 1.27 6.700012)
			(mid 0.209252 6.260636)
			(end -0.230124 5.199888)
			(stroke
				(width 0.1)
				(type default)
			)
			(layer "F.Fab")
		)
		(fp_arc
			(start 2.770124 5.199888)
			(mid 2.330748 6.260636)
			(end 1.27 6.700012)
			(stroke
				(width 0.1)
				(type default)
			)
			(layer "F.Fab")
		)
		(pad "A" thru_hole rect
			(at 0 0)
			(size 1.2192 1.2192)
			(drill 0.8128)
			(layers "*.Cu" "*.Mask")
			(remove_unused_layers no)
			(net "P5V_STBY")
			(clearance 0.0508)
			(thermal_gap 0.0508)
			(padstack
				(mode front_inner_back)
				(layer "Inner"
					(shape circle)
					(size 1.2192 1.2192)
					(clearance 0.0508)
				)
				(layer "B.Cu"
					(shape rect)
					(size 1.2192 1.2192)
					(clearance 0.0508)
				)
			)
		)
		(pad "C" thru_hole circle
			(at 2.54 0)
			(size 1.2192 1.2192)
			(drill 0.8128)
			(layers "*.Cu" "*.Mask")
			(remove_unused_layers no)
			(net "SYSTEM_FAULT_ID_LED_R2_N")
			(clearance 0.0508)
			(thermal_gap 0.0508)
		)
	)
	(footprint ""
		(layer "B.Cu")
		(at 20.862544 -27.396694 -90)
		(property "Reference" "ME8"
			(at 0 0 90)
			(layer "B.SilkS")
			(hide yes)
			(effects
				(font
					(size 1.27 1.27)
				)
				(justify mirror)
			)
		)
		(property "Value" ""
			(at 0 0 90)
			(layer "B.Fab")
			(effects
				(font
					(size 1.27 1.27)
				)
				(justify mirror)
			)
		)
		(duplicate_pad_numbers_are_jumpers no)
		(fp_line
			(start -39.500048 0)
			(end -37.976048 0)
			(stroke
				(width 0.1524)
				(type default)
			)
			(layer "B.SilkS")
		)
		(fp_line
			(start 0 0)
			(end -1.524 0)
			(stroke
				(width 0.1524)
				(type default)
			)
			(layer "B.SilkS")
		)
		(fp_line
			(start -39.500048 -1.524)
			(end -39.500048 0)
			(stroke
				(width 0.1524)
				(type default)
			)
			(layer "B.SilkS")
		)
		(fp_line
			(start 0 -1.524)
			(end 0 0)
			(stroke
				(width 0.1524)
				(type default)
			)
			(layer "B.SilkS")
		)
		(fp_line
			(start -39.500048 -6.500114)
			(end -39.500048 -4.976114)
			(stroke
				(width 0.1524)
				(type default)
			)
			(layer "B.SilkS")
		)
		(fp_line
			(start -37.976048 -6.500114)
			(end -39.500048 -6.500114)
			(stroke
				(width 0.1524)
				(type default)
			)
			(layer "B.SilkS")
		)
		(fp_line
			(start -1.524 -6.500114)
			(end 0 -6.500114)
			(stroke
				(width 0.1524)
				(type default)
			)
			(layer "B.SilkS")
		)
		(fp_line
			(start 0 -6.500114)
			(end 0 -4.976114)
			(stroke
				(width 0.1524)
				(type default)
			)
			(layer "B.SilkS")
		)
		(fp_text user "Rework version"
			(at -6.656324 -3.15468 270)
			(unlocked yes)
			(layer "B.SilkS")
			(effects
				(font
					(size 1.905 1.4224)
					(thickness 0.1524)
				)
				(justify left mirror)
			)
		)
	)
)
